FILE_TYPE = CONNECTIVITY;
{Allegro Design Entry HDL 16.6-p007 (v16-6-112F) 10/10/2012}
"PAGE_NUMBER" = 37;
0"NC";
1"PVCCIN_CPU0\g";
2"PVCCIN_CPU0\g";
3"PVCCIN_CPU0\g";
4"PVCCIN_CPU0\g";
5"GND\g";
6"PVCCIN_CPU0\g";
7"PVCCIO_CPU0\g";
8"VSENSE_PVCCIN_CPU0_SKT_VSEN";
9"VSENSE_PVCCIN_CPU0_SKT_VRTN";
10"VSENSE_VCCINR2PMAX_CPU0";
11"VSENSE_PMAX_CPU0";
%"PVCCIN_CPU0"
"1","(-7125,4350)","0","mstr_symbols","I295";
;
BODY_TYPE"PLUMBING"
VOLTAGE"2.0V"
CDS_LIB"mstr_symbols"
HDL_POWER"PVCCIN_CPU0";
"G\NAC"1;
%"PVCCIN_CPU0"
"1","(-5250,4275)","0","mstr_symbols","I296";
;
VOLTAGE"2.0V"
CDS_LIB"mstr_symbols"
BODY_TYPE"PLUMBING"
HDL_POWER"PVCCIN_CPU0";
"G\NAC"2;
%"PVCCIN_CPU0"
"1","(-3375,4350)","0","mstr_symbols","I300";
;
VOLTAGE"2.0V"
BODY_TYPE"PLUMBING"
CDS_LIB"mstr_symbols"
HDL_POWER"PVCCIN_CPU0";
"G\NAC"3;
%"PVCCIN_CPU0"
"1","(-1500,4325)","0","mstr_symbols","I301";
;
BODY_TYPE"PLUMBING"
VOLTAGE"2.0V"
CDS_LIB"mstr_symbols"
HDL_POWER"PVCCIN_CPU0";
"G\NAC"4;
%"GND"
"1","(-375,525)","0","mstr_symbols","I302";
;
BODY_TYPE"PLUMBING"
VOLTAGE"0.0V"
SIZE"1B"
HDL_POWER"GND"
CDS_LIB"mstr_symbols";
"A\NAC"5;
%"RES"
"2","(-375,750)","0","mstr_discrete","I303";
;
CDS_SEC"1"
WATTAGE"1/16W"
MATERIAL"CHIP"
PACK_TYPE"0402"
TOLERANCE"0.1%"
VALUE"249"
PART_NUMBER"G85996-031"
LOCATION"R5D5"
CDS_LIB"mstr_discrete"
CDS_LOCATION"R5D5"
ROOM"CPU0"
SEC"1"
SEC_TYPE"0402"
BOM_COST"PROC_SOCKET";
"A"
$PN"1"11;
"B"
$PN"2"5;
%"PVCCIN_CPU0"
"1","(-775,1625)","0","mstr_symbols","I305";
;
HDL_POWER"PVCCIN_CPU0"
BODY_TYPE"PLUMBING"
CDS_LIB"mstr_symbols"
VOLTAGE"2.0V";
"G\NAC"6;
%"RES"
"2","(-775,1350)","0","mstr_discrete","I309";
;
CDS_SEC"1"
WATTAGE"1/10W"
MATERIAL"CHIP"
PART_NUMBER"G22026-050"
LOCATION"R5P1"
VALUE"100.0K"
PACK_TYPE"0603"
TOLERANCE"1%"
CDS_LIB"mstr_discrete"
CDS_LOCATION"R5P1"
ROOM"CPU0"
BOM_COST"PROC_SOCKET"
SEC"1"
SEC_TYPE"0603";
"A"
$PN"1"6;
"B"
$PN"2"10;
%"SKX_EXT_B"
"18","(-6200,2475)","0","chpset_lib","I310";
;
CDS_SEC"18"
PART_NUMBER"TBD"
MATERIAL"IC"
LOCATION"U5D1"
CDS_LIB"chpset_lib"
PACK_TYPE"BGA1"
ROOM"CPU0"
CDS_LOCATION"U5D1"
SEC"18"
SEC_TYPE"BGA1";
"VCCIN<130>"
$PN"BN78"2;
"VCCIN<131>"
$PN"BN76"2;
"VCCIN<132>"
$PN"BN74"2;
"VCCIN<133>"
$PN"BN72"2;
"VCCIN<134>"
$PN"BN70"2;
"VCCIN<135>"
$PN"BN68"2;
"VCCIN<136>"
$PN"BN66"2;
"VCCIN<137>"
$PN"BN64"2;
"VCCIN<138>"
$PN"BN62"2;
"VCCIN<139>"
$PN"BN60"2;
"VCCIN<140>"
$PN"BM83"2;
"VCCIN<141>"
$PN"BM81"2;
"VCCIN<142>"
$PN"BM79"2;
"VCCIN<143>"
$PN"BM77"2;
"VCCIN<144>"
$PN"BM75"2;
"VCCIN<145>"
$PN"BM73"2;
"VCCIN<146>"
$PN"BM71"2;
"VCCIN<147>"
$PN"BM69"2;
"VCCIN<148>"
$PN"BM67"2;
"VCCIN<149>"
$PN"BM65"2;
"VCCIN<150>"
$PN"BM63"2;
"VCCIN<151>"
$PN"BM61"2;
"VCCIN<152>"
$PN"BL84"2;
"VCCIN<153>"
$PN"BL62"2;
"VCCIN<154>"
$PN"BL60"2;
"VCCIN<155>"
$PN"BK83"2;
"VCCIN<156>"
$PN"BK81"2;
"VCCIN<157>"
$PN"BK79"2;
"VCCIN<158>"
$PN"BK77"2;
"VCCIN<159>"
$PN"BK75"2;
"VCCIN<160>"
$PN"BK73"2;
"VCCIN<161>"
$PN"BK71"2;
"VCCIN<162>"
$PN"BK69"2;
"VCCIN<163>"
$PN"BK67"2;
"VCCIN<164>"
$PN"BK65"2;
"VCCIN<165>"
$PN"BK63"2;
"VCCIN<166>"
$PN"BK61"2;
"VCCIN<167>"
$PN"BJ84"2;
"VCCIN<168>"
$PN"BJ82"2;
"VCCIN<169>"
$PN"BJ80"2;
"VCCIN<170>"
$PN"BJ78"2;
"VCCIN<171>"
$PN"BJ76"2;
"VCCIN<172>"
$PN"BJ74"2;
"VCCIN<173>"
$PN"BJ72"2;
"VCCIN<174>"
$PN"BJ70"2;
"VCCIN<175>"
$PN"BJ68"2;
"VCCIN<176>"
$PN"BJ66"2;
"VCCIN<177>"
$PN"BJ64"2;
"VCCIN<178>"
$PN"BJ62"2;
"VCCIN<179>"
$PN"BJ60"2;
"VCCIN<180>"
$PN"BH83"2;
"VCCIN<181>"
$PN"BH81"2;
"VCCIN<182>"
$PN"BH79"2;
"VCCIN<183>"
$PN"BH77"2;
"VCCIN<184>"
$PN"BH75"2;
"VCCIN<185>"
$PN"BH73"2;
"VCCIN<186>"
$PN"BH71"2;
"VCCIN<187>"
$PN"BH69"2;
"VCCIN<188>"
$PN"BH67"2;
"VCCIN<189>"
$PN"BH65"2;
"VCCIN<190>"
$PN"BH63"2;
"VCCIN<191>"
$PN"BH61"2;
"VCCIN<192>"
$PN"BG84"2;
"VCCIN<193>"
$PN"BG70"2;
"VCCIN<194>"
$PN"BG68"2;
"VCCIN<195>"
$PN"BG66"2;
"VCCIN<196>"
$PN"BG64"2;
"VCCIN<197>"
$PN"BG62"2;
"VCCIN<198>"
$PN"BG60"2;
"VCCIN<199>"
$PN"BF85"1;
"VCCIN<200>"
$PN"BF83"1;
"VCCIN<201>"
$PN"BF81"1;
"VCCIN<202>"
$PN"BF79"1;
"VCCIN<203>"
$PN"BF77"1;
"VCCIN<204>"
$PN"BF75"1;
"VCCIN<205>"
$PN"BF73"1;
"VCCIN<206>"
$PN"BF61"1;
"VCCIN<207>"
$PN"BE84"1;
"VCCIN<208>"
$PN"BE82"1;
"VCCIN<209>"
$PN"BE80"1;
"VCCIN<210>"
$PN"BE78"1;
"VCCIN<211>"
$PN"BE76"1;
"VCCIN<212>"
$PN"BE74"1;
"VCCIN<213>"
$PN"BE72"1;
"VCCIN<214>"
$PN"BE62"1;
"VCCIN<215>"
$PN"BE60"1;
"VCCIN<216>"
$PN"BD85"1;
"VCCIN<217>"
$PN"BD83"1;
"VCCIN<218>"
$PN"BD81"1;
"VCCIN<219>"
$PN"BD79"1;
"VCCIN<220>"
$PN"BD77"1;
"VCCIN<221>"
$PN"BD75"1;
"VCCIN<222>"
$PN"BD73"1;
"VCCIN<223>"
$PN"BD61"1;
"VCCIN<224>"
$PN"BC84"1;
"VCCIN<225>"
$PN"BC62"1;
"VCCIN<226>"
$PN"BC60"1;
"VCCIN<227>"
$PN"BB85"1;
"VCCIN<228>"
$PN"BB61"1;
"VCCIN<229>"
$PN"BA60"1;
"VCCIN<230>"
$PN"AY61"1;
"VCCIN<231>"
$PN"AW60"1;
"VCCIN<232>"
$PN"AV61"1;
"VCCIN<233>"
$PN"AV59"1;
"VCCIN<234>"
$PN"AU60"1;
"VCCIN<235>"
$PN"AU58"1;
"VCCIN<236>"
$PN"AT59"1;
"VCCIN<237>"
$PN"AT57"1;
"VCCIN<238>"
$PN"AR58"1;
"VCCIN<239>"
$PN"AR56"1;
"VCCIN<240>"
$PN"AP57"1;
"VCCIN<241>"
$PN"AP55"1;
"VCCIN<242>"
$PN"AN56"1;
"VCCIN<243>"
$PN"AN54"1;
"VCCIN<244>"
$PN"AN32"1;
"VCCIN<245>"
$PN"AM55"1;
"VCCIN<246>"
$PN"AM53"1;
"VCCIN<247>"
$PN"AM33"1;
"VCCIN<248>"
$PN"AL54"1;
"VCCIN<249>"
$PN"AL52"1;
"VCCIN<250>"
$PN"AL50"1;
"VCCIN<251>"
$PN"AL48"1;
"VCCIN<252>"
$PN"AL46"1;
"VCCIN<253>"
$PN"AL34"1;
"VCCIN<254>"
$PN"AK53"1;
"VCCIN<255>"
$PN"AK51"1;
"VCCIN<256>"
$PN"AK49"1;
"VCCIN<257>"
$PN"AK47"1;
"VCCIN<258>"
$PN"AK45"1;
"VCCIN<259>"
$PN"AK35"1;
"VCCIN<260>"
$PN"AJ36"1;
"VCCIN<261>"
$PN"AH41"1;
"VCCIN<262>"
$PN"AH39"1;
"VCCIN<263>"
$PN"AH37"1;
"VCCIN<264>"
$PN"AG42"1;
"VCCIN<265>"
$PN"AG40"1;
"VCCIN<266>"
$PN"AG38"1;
"VCCIN<267>"
$PN"AF43"1;
%"SKX_EXT_B"
"19","(-2425,2475)","0","chpset_lib","I311";
;
CDS_SEC"19"
PART_NUMBER"TBD"
MATERIAL"IC"
LOCATION"U5D1"
CDS_LIB"chpset_lib"
ROOM"CPU0"
CDS_LOCATION"U5D1"
SEC"19"
SEC_TYPE"BGA1"
PACK_TYPE"BGA1";
"VSS_VCCIN_SENSE"
$PN"AY85"9;
"VSENSEPMAX"
$PN"AD41"11;
"VCCIN_SENSE"
$PN"BA86"8;
"VCCINPMAX<0>"
$PN"AW86"10;
"VCCINPMAX<1>"
$PN"AV85"10;
"VCCIN<0>"
$PN"CY49"4;
"VCCIN<1>"
$PN"CY47"4;
"VCCIN<2>"
$PN"CW50"4;
"VCCIN<3>"
$PN"CW48"4;
"VCCIN<4>"
$PN"CW46"4;
"VCCIN<5>"
$PN"CV51"4;
"VCCIN<6>"
$PN"CU54"4;
"VCCIN<7>"
$PN"CU52"4;
"VCCIN<8>"
$PN"CU42"4;
"VCCIN<9>"
$PN"CU40"4;
"VCCIN<10>"
$PN"CU38"4;
"VCCIN<11>"
$PN"CT55"4;
"VCCIN<12>"
$PN"CT53"4;
"VCCIN<13>"
$PN"CT41"4;
"VCCIN<14>"
$PN"CT39"4;
"VCCIN<15>"
$PN"CT37"4;
"VCCIN<16>"
$PN"CR56"4;
"VCCIN<17>"
$PN"CR54"4;
"VCCIN<18>"
$PN"CR34"4;
"VCCIN<19>"
$PN"CP57"4;
"VCCIN<20>"
$PN"CP55"4;
"VCCIN<21>"
$PN"CP33"4;
"VCCIN<22>"
$PN"CN58"4;
"VCCIN<23>"
$PN"CN56"4;
"VCCIN<24>"
$PN"CM59"4;
"VCCIN<25>"
$PN"CM57"4;
"VCCIN<26>"
$PN"CL60"4;
"VCCIN<27>"
$PN"CL58"4;
"VCCIN<28>"
$PN"CK61"4;
"VCCIN<29>"
$PN"CK59"4;
"VCCIN<30>"
$PN"CJ60"4;
"VCCIN<31>"
$PN"CH85"4;
"VCCIN<32>"
$PN"CH61"4;
"VCCIN<33>"
$PN"CG84"4;
"VCCIN<34>"
$PN"CG60"4;
"VCCIN<35>"
$PN"CF85"4;
"VCCIN<36>"
$PN"CF61"4;
"VCCIN<37>"
$PN"CE84"4;
"VCCIN<38>"
$PN"CE60"4;
"VCCIN<39>"
$PN"CD85"4;
"VCCIN<40>"
$PN"CD83"4;
"VCCIN<41>"
$PN"CD61"4;
"VCCIN<42>"
$PN"CC84"4;
"VCCIN<43>"
$PN"CC62"4;
"VCCIN<44>"
$PN"CC60"4;
"VCCIN<45>"
$PN"CB83"4;
"VCCIN<46>"
$PN"CB81"4;
"VCCIN<47>"
$PN"CB79"4;
"VCCIN<48>"
$PN"CB77"4;
"VCCIN<49>"
$PN"CB75"4;
"VCCIN<50>"
$PN"CB73"4;
"VCCIN<51>"
$PN"CB61"4;
"VCCIN<52>"
$PN"CA84"4;
"VCCIN<53>"
$PN"CA82"4;
"VCCIN<54>"
$PN"CA80"4;
"VCCIN<55>"
$PN"CA78"4;
"VCCIN<56>"
$PN"CA76"4;
"VCCIN<57>"
$PN"CA74"4;
"VCCIN<58>"
$PN"CA72"4;
"VCCIN<59>"
$PN"CA62"4;
"VCCIN<60>"
$PN"CA60"4;
"VCCIN<61>"
$PN"BY83"3;
"VCCIN<62>"
$PN"BY81"3;
"VCCIN<63>"
$PN"BY79"3;
"VCCIN<64>"
$PN"BY77"3;
"VCCIN<65>"
$PN"BY75"3;
"VCCIN<66>"
$PN"BY73"3;
"VCCIN<67>"
$PN"BY61"3;
"VCCIN<68>"
$PN"BW84"3;
"VCCIN<69>"
$PN"BW70"3;
"VCCIN<70>"
$PN"BW68"3;
"VCCIN<71>"
$PN"BW66"3;
"VCCIN<72>"
$PN"BW64"3;
"VCCIN<73>"
$PN"BW62"3;
"VCCIN<74>"
$PN"BW60"3;
"VCCIN<75>"
$PN"BV83"3;
"VCCIN<76>"
$PN"BV81"3;
"VCCIN<77>"
$PN"BV79"3;
"VCCIN<78>"
$PN"BV77"3;
"VCCIN<79>"
$PN"BV75"3;
"VCCIN<80>"
$PN"BV73"3;
"VCCIN<81>"
$PN"BV71"3;
"VCCIN<82>"
$PN"BV69"3;
"VCCIN<83>"
$PN"BV67"3;
"VCCIN<84>"
$PN"BV65"3;
"VCCIN<85>"
$PN"BV63"3;
"VCCIN<86>"
$PN"BV61"3;
"VCCIN<87>"
$PN"BU84"3;
"VCCIN<88>"
$PN"BU82"3;
"VCCIN<89>"
$PN"BU80"3;
"VCCIN<90>"
$PN"BU78"3;
"VCCIN<91>"
$PN"BU76"3;
"VCCIN<92>"
$PN"BU74"3;
"VCCIN<93>"
$PN"BU72"3;
"VCCIN<94>"
$PN"BU70"3;
"VCCIN<95>"
$PN"BU68"3;
"VCCIN<96>"
$PN"BU66"3;
"VCCIN<97>"
$PN"BU64"3;
"VCCIN<98>"
$PN"BU62"3;
"VCCIN<99>"
$PN"BU60"3;
"VCCIN<100>"
$PN"BT83"3;
"VCCIN<101>"
$PN"BT81"3;
"VCCIN<102>"
$PN"BT79"3;
"VCCIN<103>"
$PN"BT77"3;
"VCCIN<104>"
$PN"BT75"3;
"VCCIN<105>"
$PN"BT73"3;
"VCCIN<106>"
$PN"BT71"3;
"VCCIN<107>"
$PN"BT69"3;
"VCCIN<108>"
$PN"BT67"3;
"VCCIN<109>"
$PN"BT65"3;
"VCCIN<110>"
$PN"BT63"3;
"VCCIN<111>"
$PN"BT61"3;
"VCCIN<112>"
$PN"BR84"3;
"VCCIN<113>"
$PN"BR62"3;
"VCCIN<114>"
$PN"BR60"3;
"VCCIN<115>"
$PN"BP83"3;
"VCCIN<116>"
$PN"BP81"3;
"VCCIN<117>"
$PN"BP79"3;
"VCCIN<118>"
$PN"BP77"3;
"VCCIN<119>"
$PN"BP75"3;
"VCCIN<120>"
$PN"BP73"3;
"VCCIN<121>"
$PN"BP71"3;
"VCCIN<122>"
$PN"BP69"3;
"VCCIN<123>"
$PN"BP67"3;
"VCCIN<124>"
$PN"BP65"3;
"VCCIN<125>"
$PN"BP63"3;
"VCCIN<126>"
$PN"BP61"3;
"VCCIN<127>"
$PN"BN84"3;
"VCCIN<128>"
$PN"BN82"3;
"VCCIN<129>"
$PN"BN80"3;
%"RES"
"2","(-375,1125)","0","mstr_discrete","I312";
;
CDS_SEC"1"
CDS_LOCATION"R5D6"
LOCATION"R5D6"
VALUE"10.0"
PART_NUMBER"G21796-066"
PACK_TYPE"0402"
TOLERANCE"1%"
WATTAGE"1/16W"
MATERIAL"EMPTY"
CDS_LIB"mstr_discrete"
ROOM"CPU0"
SEC"1"
SEC_TYPE"0402";
"A"
$PN"1"7;
"B"
$PN"2"11;
%"PVCCIO_CPU0"
"1","(-375,1450)","0","mstr_symbols","I313";
;
BODY_TYPE"PLUMBING"
CDS_LIB"mstr_symbols"
VOLTAGE"1.1V"
HDL_POWER"PVCCIO_CPU0";
"G\NAC"7;
END.
